(kicad_pcb
	(version 20260206)
	(generator "pcbnew")
	(generator_version "10.0")
	(general
		(thickness 1.6)
		(legacy_teardrops no)
	)
	(paper "A4")
	(title_block
		(title "01162023_DA0F0TEBIF0_F0T_Expander_BD_F_brd_V02_OCP.brd")
		(comment 1 "Grand Teton / footprint 6619 of 9728 (PEX0), pads 356-474 of 2397")
	)
	(layers
		(0 "F.Cu" signal "TOP")
		(4 "In1.Cu" signal "GND")
		(6 "In2.Cu" signal "VCC")
		(8 "In3.Cu" signal "VCC1")
		(10 "In4.Cu" signal "GND1")
		(12 "In5.Cu" signal "IN1")
		(14 "In6.Cu" signal "GND2")
		(16 "In7.Cu" signal "IN2")
		(18 "In8.Cu" signal "GND3")
		(20 "In9.Cu" signal "IN3")
		(22 "In10.Cu" signal "GND4")
		(24 "In11.Cu" signal "IN4")
		(26 "In12.Cu" signal "GND5")
		(28 "In13.Cu" signal "IN5")
		(30 "In14.Cu" signal "GND6")
		(32 "In15.Cu" signal "IN6")
		(34 "In16.Cu" signal "GND7")
		(2 "B.Cu" signal "BOTTOM")
		(9 "F.Adhes" user "F.Adhesive")
		(11 "B.Adhes" user "B.Adhesive")
		(13 "F.Paste" user "Package Geometry/Pastemask Top")
		(15 "B.Paste" user "Package Geometry/Pastemask Bottom")
		(5 "F.SilkS" user "Ref Des/Silkscreen Top")
		(7 "B.SilkS" user "Ref Des/Silkscreen Bottom")
		(1 "F.Mask" user "Board Geometry/Soldermask Top")
		(3 "B.Mask" user "Board Geometry/Soldermask Bottom")
		(17 "Dwgs.User" user "User.Drawings")
		(19 "Cmts.User" user "User.Comments")
		(21 "Eco1.User" user "User.Eco1")
		(23 "Eco2.User" user "User.Eco2")
		(25 "Edge.Cuts" user "Board Geometry/Outline")
		(27 "Margin" user)
		(31 "F.CrtYd" user "Package Geometry/Place Bound Top")
		(29 "B.CrtYd" user "Package Geometry/Place Bound Bottom")
		(35 "F.Fab" user "Ref Des/Assembly Top")
		(33 "B.Fab" user "Ref Des/Assembly Bottom")
	)
	(footprint ""
		(layer "F.Cu")
		(at 59.649868 -295.89984)
		(property "Reference" "PEX0"
			(at -3.360166 35.566858 0)
			(unlocked yes)
			(layer "F.SilkS")
			(effects
				(font
					(size 2.032 1.524)
					(thickness 0.1524)
				)
				(justify left)
			)
		)
		(property "Value" ""
			(at 0 0 0)
			(layer "F.Fab")
			(effects
				(font
					(size 1.27 1.27)
				)
			)
		)
		(duplicate_pad_numbers_are_jumpers no)
		(pad "AG15" smd circle
			(at -9.500108 1.89992)
			(size 0.4572 0.4572)
			(layers "F.Cu" "F.Mask" "F.Paste")
			(net "P0V8_PEX0")
		)
		(pad "AG16" smd circle
			(at -8.549894 1.89992)
			(size 0.4572 0.4572)
			(layers "F.Cu" "F.Mask" "F.Paste")
			(net "GND")
		)
		(pad "AG17" smd circle
			(at -7.599934 1.89992)
			(size 0.4572 0.4572)
			(layers "F.Cu" "F.Mask" "F.Paste")
			(net "P0V8_PEX0")
		)
		(pad "AG18" smd circle
			(at -6.649974 1.89992)
			(size 0.4572 0.4572)
			(layers "F.Cu" "F.Mask" "F.Paste")
			(net "GND")
		)
		(pad "AG19" smd circle
			(at -5.700014 1.89992)
			(size 0.4572 0.4572)
			(layers "F.Cu" "F.Mask" "F.Paste")
			(net "P0V8_PEX0")
		)
		(pad "AG20" smd circle
			(at -4.750054 1.89992)
			(size 0.4572 0.4572)
			(layers "F.Cu" "F.Mask" "F.Paste")
			(net "GND")
		)
		(pad "AG21" smd circle
			(at -3.800094 1.89992)
			(size 0.4572 0.4572)
			(layers "F.Cu" "F.Mask" "F.Paste")
			(net "P0V8_PEX0")
		)
		(pad "AG22" smd circle
			(at -2.84988 1.89992)
			(size 0.4572 0.4572)
			(layers "F.Cu" "F.Mask" "F.Paste")
			(net "GND")
		)
		(pad "AG23" smd circle
			(at -1.89992 1.89992)
			(size 0.4572 0.4572)
			(layers "F.Cu" "F.Mask" "F.Paste")
			(net "P0V8_PEX0")
		)
		(pad "AG24" smd circle
			(at -0.94996 1.89992)
			(size 0.4572 0.4572)
			(layers "F.Cu" "F.Mask" "F.Paste")
			(net "GND")
		)
		(pad "AG25" smd circle
			(at 0 1.89992)
			(size 0.4572 0.4572)
			(layers "F.Cu" "F.Mask" "F.Paste")
			(net "P0V8_PEX0")
		)
		(pad "AG26" smd circle
			(at 0.94996 1.89992)
			(size 0.4572 0.4572)
			(layers "F.Cu" "F.Mask" "F.Paste")
			(net "GND")
		)
		(pad "AG27" smd circle
			(at 1.89992 1.89992)
			(size 0.4572 0.4572)
			(layers "F.Cu" "F.Mask" "F.Paste")
			(net "P0V8_PEX0")
		)
		(pad "AG28" smd circle
			(at 2.84988 1.89992)
			(size 0.4572 0.4572)
			(layers "F.Cu" "F.Mask" "F.Paste")
			(net "GND")
		)
		(pad "AG29" smd circle
			(at 3.800094 1.89992)
			(size 0.4572 0.4572)
			(layers "F.Cu" "F.Mask" "F.Paste")
			(net "P0V8_PEX0")
		)
		(pad "AG30" smd circle
			(at 4.750054 1.89992)
			(size 0.4572 0.4572)
			(layers "F.Cu" "F.Mask" "F.Paste")
			(net "GND")
		)
		(pad "AG31" smd circle
			(at 5.700014 1.89992)
			(size 0.4572 0.4572)
			(layers "F.Cu" "F.Mask" "F.Paste")
			(net "P0V8_PEX0")
		)
		(pad "AG32" smd circle
			(at 6.649974 1.89992)
			(size 0.4572 0.4572)
			(layers "F.Cu" "F.Mask" "F.Paste")
			(net "GND")
		)
		(pad "AG33" smd circle
			(at 7.599934 1.89992)
			(size 0.4572 0.4572)
			(layers "F.Cu" "F.Mask" "F.Paste")
			(net "P0V8_PEX0")
		)
		(pad "AG34" smd circle
			(at 8.549894 1.89992)
			(size 0.4572 0.4572)
			(layers "F.Cu" "F.Mask" "F.Paste")
			(net "GND")
		)
		(pad "AG35" smd circle
			(at 9.500108 1.89992)
			(size 0.4572 0.4572)
			(layers "F.Cu" "F.Mask" "F.Paste")
			(net "GND")
		)
		(pad "AG36" smd circle
			(at 10.450068 1.89992)
			(size 0.4572 0.4572)
			(layers "F.Cu" "F.Mask" "F.Paste")
			(net "P1V25_PEX0")
		)
		(pad "AG37" smd circle
			(at 11.400028 1.89992)
			(size 0.4572 0.4572)
			(layers "F.Cu" "F.Mask" "F.Paste")
			(net "GND")
		)
		(pad "AG38" smd circle
			(at 12.349988 1.89992)
			(size 0.4572 0.4572)
			(layers "F.Cu" "F.Mask" "F.Paste")
			(net "P1V25_SERDES_VDDPLL_PEX0")
		)
		(pad "AG39" smd circle
			(at 13.299948 1.89992)
			(size 0.4572 0.4572)
			(layers "F.Cu" "F.Mask" "F.Paste")
			(net "GND")
		)
		(pad "AG40" smd circle
			(at 14.249908 1.89992)
			(size 0.4572 0.4572)
			(layers "F.Cu" "F.Mask" "F.Paste")
			(net "GND")
		)
		(pad "AG41" smd circle
			(at 15.200122 1.89992)
			(size 0.4572 0.4572)
			(layers "F.Cu" "F.Mask" "F.Paste")
			(net "GND")
		)
		(pad "AG42" smd circle
			(at 16.150082 1.89992)
			(size 0.4572 0.4572)
			(layers "F.Cu" "F.Mask" "F.Paste")
			(net "GND")
		)
		(pad "AG43" smd circle
			(at 17.100042 1.89992)
			(size 0.4572 0.4572)
			(layers "F.Cu" "F.Mask" "F.Paste")
			(net "Net_2824")
		)
		(pad "AG44" smd circle
			(at 18.050002 1.89992)
			(size 0.4572 0.4572)
			(layers "F.Cu" "F.Mask" "F.Paste")
			(net "Net_2808")
		)
		(pad "AG45" smd circle
			(at 18.999962 1.89992)
			(size 0.4572 0.4572)
			(layers "F.Cu" "F.Mask" "F.Paste")
			(net "GND")
		)
		(pad "AG46" smd circle
			(at 19.949922 1.89992)
			(size 0.4572 0.4572)
			(layers "F.Cu" "F.Mask" "F.Paste")
			(net "Net_2792")
		)
		(pad "AG47" smd circle
			(at 20.899882 1.89992)
			(size 0.4572 0.4572)
			(layers "F.Cu" "F.Mask" "F.Paste")
			(net "Net_2776")
		)
		(pad "AG48" smd circle
			(at 21.850096 1.89992)
			(size 0.4572 0.4572)
			(layers "F.Cu" "F.Mask" "F.Paste")
			(net "GND")
		)
		(pad "AG49" smd circle
			(at 22.800056 1.89992)
			(size 0.4572 0.4572)
			(layers "F.Cu" "F.Mask" "F.Paste")
			(net "GND")
		)
		(pad "AH1" smd circle
			(at -22.800056 2.84988)
			(size 0.4572 0.4572)
			(layers "F.Cu" "F.Mask" "F.Paste")
			(net "GND")
		)
		(pad "AH2" smd circle
			(at -21.850096 2.84988)
			(size 0.4572 0.4572)
			(layers "F.Cu" "F.Mask" "F.Paste")
			(net "GND")
		)
		(pad "AH3" smd circle
			(at -20.899882 2.84988)
			(size 0.4572 0.4572)
			(layers "F.Cu" "F.Mask" "F.Paste")
			(net "GND")
		)
		(pad "AH4" smd circle
			(at -19.949922 2.84988)
			(size 0.4572 0.4572)
			(layers "F.Cu" "F.Mask" "F.Paste")
			(net "Net_2837")
		)
		(pad "AH5" smd circle
			(at -18.999962 2.84988)
			(size 0.4572 0.4572)
			(layers "F.Cu" "F.Mask" "F.Paste")
			(net "Net_2838")
		)
		(pad "AH6" smd circle
			(at -18.050002 2.84988)
			(size 0.4572 0.4572)
			(layers "F.Cu" "F.Mask" "F.Paste")
			(net "GND")
		)
		(pad "AH7" smd circle
			(at -17.100042 2.84988)
			(size 0.4572 0.4572)
			(layers "F.Cu" "F.Mask" "F.Paste")
			(net "SPI_PEX0_CLK")
		)
		(pad "AH8" smd circle
			(at -16.150082 2.84988)
			(size 0.4572 0.4572)
			(layers "F.Cu" "F.Mask" "F.Paste")
			(net "SPI_PEX0_SDIO3")
		)
		(pad "AH9" smd circle
			(at -15.200122 2.84988)
			(size 0.4572 0.4572)
			(layers "F.Cu" "F.Mask" "F.Paste")
			(net "GND")
		)
		(pad "AH10" smd circle
			(at -14.249908 2.84988)
			(size 0.4572 0.4572)
			(layers "F.Cu" "F.Mask" "F.Paste")
			(net "P1V8_PEX")
		)
		(pad "AH11" smd circle
			(at -13.299948 2.84988)
			(size 0.4572 0.4572)
			(layers "F.Cu" "F.Mask" "F.Paste")
			(net "GND")
		)
		(pad "AH12" smd circle
			(at -12.349988 2.84988)
			(size 0.4572 0.4572)
			(layers "F.Cu" "F.Mask" "F.Paste")
			(net "PCEPLL6_VDDA18_PEX0")
		)
		(pad "AH13" smd circle
			(at -11.400028 2.84988)
			(size 0.4572 0.4572)
			(layers "F.Cu" "F.Mask" "F.Paste")
			(net "GND")
		)
		(pad "AH14" smd circle
			(at -10.450068 2.84988)
			(size 0.4572 0.4572)
			(layers "F.Cu" "F.Mask" "F.Paste")
			(net "P0V8_PEX0")
		)
		(pad "AH15" smd circle
			(at -9.500108 2.84988)
			(size 0.4572 0.4572)
			(layers "F.Cu" "F.Mask" "F.Paste")
			(net "GND")
		)
		(pad "AH16" smd circle
			(at -8.549894 2.84988)
			(size 0.4572 0.4572)
			(layers "F.Cu" "F.Mask" "F.Paste")
			(net "P0V8_SERDES_VDDA_PEX0")
		)
		(pad "AH17" smd circle
			(at -7.599934 2.84988)
			(size 0.4572 0.4572)
			(layers "F.Cu" "F.Mask" "F.Paste")
			(net "P0V8_SERDES_VDDA_PEX0")
		)
		(pad "AH18" smd circle
			(at -6.649974 2.84988)
			(size 0.4572 0.4572)
			(layers "F.Cu" "F.Mask" "F.Paste")
			(net "P0V8_SERDES_VDDA_PEX0")
		)
		(pad "AH19" smd circle
			(at -5.700014 2.84988)
			(size 0.4572 0.4572)
			(layers "F.Cu" "F.Mask" "F.Paste")
			(net "P0V8_SERDES_VDDA_PEX0")
		)
		(pad "AH20" smd circle
			(at -4.750054 2.84988)
			(size 0.4572 0.4572)
			(layers "F.Cu" "F.Mask" "F.Paste")
			(net "P0V8_SERDES_VDDA_PEX0")
		)
		(pad "AH21" smd circle
			(at -3.800094 2.84988)
			(size 0.4572 0.4572)
			(layers "F.Cu" "F.Mask" "F.Paste")
			(net "P0V8_SERDES_VDDA_PEX0")
		)
		(pad "AH22" smd circle
			(at -2.84988 2.84988)
			(size 0.4572 0.4572)
			(layers "F.Cu" "F.Mask" "F.Paste")
			(net "P0V8_SERDES_VDDA_PEX0")
		)
		(pad "AH23" smd circle
			(at -1.89992 2.84988)
			(size 0.4572 0.4572)
			(layers "F.Cu" "F.Mask" "F.Paste")
			(net "P0V8_SERDES_VDDA_PEX0")
		)
		(pad "AH24" smd circle
			(at -0.94996 2.84988)
			(size 0.4572 0.4572)
			(layers "F.Cu" "F.Mask" "F.Paste")
			(net "P0V8_SERDES_VDDA_PEX0")
		)
		(pad "AH25" smd circle
			(at 0 2.84988)
			(size 0.4572 0.4572)
			(layers "F.Cu" "F.Mask" "F.Paste")
			(net "P0V8_SERDES_VDDA_PEX0")
		)
		(pad "AH26" smd circle
			(at 0.94996 2.84988)
			(size 0.4572 0.4572)
			(layers "F.Cu" "F.Mask" "F.Paste")
			(net "P0V8_SERDES_VDDA_PEX0")
		)
		(pad "AH27" smd circle
			(at 1.89992 2.84988)
			(size 0.4572 0.4572)
			(layers "F.Cu" "F.Mask" "F.Paste")
			(net "P0V8_SERDES_VDDA_PEX0")
		)
		(pad "AH28" smd circle
			(at 2.84988 2.84988)
			(size 0.4572 0.4572)
			(layers "F.Cu" "F.Mask" "F.Paste")
			(net "P0V8_SERDES_VDDA_PEX0")
		)
		(pad "AH29" smd circle
			(at 3.800094 2.84988)
			(size 0.4572 0.4572)
			(layers "F.Cu" "F.Mask" "F.Paste")
			(net "P0V8_SERDES_VDDA_PEX0")
		)
		(pad "AH30" smd circle
			(at 4.750054 2.84988)
			(size 0.4572 0.4572)
			(layers "F.Cu" "F.Mask" "F.Paste")
			(net "P0V8_SERDES_VDDA_PEX0")
		)
		(pad "AH31" smd circle
			(at 5.700014 2.84988)
			(size 0.4572 0.4572)
			(layers "F.Cu" "F.Mask" "F.Paste")
			(net "P0V8_SERDES_VDDA_PEX0")
		)
		(pad "AH32" smd circle
			(at 6.649974 2.84988)
			(size 0.4572 0.4572)
			(layers "F.Cu" "F.Mask" "F.Paste")
			(net "P0V8_SERDES_VDDA_PEX0")
		)
		(pad "AH33" smd circle
			(at 7.599934 2.84988)
			(size 0.4572 0.4572)
			(layers "F.Cu" "F.Mask" "F.Paste")
			(net "P0V8_SERDES_VDDA_PEX0")
		)
		(pad "AH34" smd circle
			(at 8.549894 2.84988)
			(size 0.4572 0.4572)
			(layers "F.Cu" "F.Mask" "F.Paste")
			(net "GND")
		)
		(pad "AH35" smd circle
			(at 9.500108 2.84988)
			(size 0.4572 0.4572)
			(layers "F.Cu" "F.Mask" "F.Paste")
			(net "GND")
		)
		(pad "AH36" smd circle
			(at 10.450068 2.84988)
			(size 0.4572 0.4572)
			(layers "F.Cu" "F.Mask" "F.Paste")
			(net "GND")
		)
		(pad "AH37" smd circle
			(at 11.400028 2.84988)
			(size 0.4572 0.4572)
			(layers "F.Cu" "F.Mask" "F.Paste")
			(net "GND")
		)
		(pad "AH38" smd circle
			(at 12.349988 2.84988)
			(size 0.4572 0.4572)
			(layers "F.Cu" "F.Mask" "F.Paste")
			(net "GND")
		)
		(pad "AH39" smd circle
			(at 13.299948 2.84988)
			(size 0.4572 0.4572)
			(layers "F.Cu" "F.Mask" "F.Paste")
			(net "GND")
		)
		(pad "AH40" smd circle
			(at 14.249908 2.84988)
			(size 0.4572 0.4572)
			(layers "F.Cu" "F.Mask" "F.Paste")
			(net "GND")
		)
		(pad "AH41" smd circle
			(at 15.200122 2.84988)
			(size 0.4572 0.4572)
			(layers "F.Cu" "F.Mask" "F.Paste")
			(net "Net_2825")
		)
		(pad "AH42" smd circle
			(at 16.150082 2.84988)
			(size 0.4572 0.4572)
			(layers "F.Cu" "F.Mask" "F.Paste")
			(net "Net_2809")
		)
		(pad "AH43" smd circle
			(at 17.100042 2.84988)
			(size 0.4572 0.4572)
			(layers "F.Cu" "F.Mask" "F.Paste")
			(net "GND")
		)
		(pad "AH44" smd circle
			(at 18.050002 2.84988)
			(size 0.4572 0.4572)
			(layers "F.Cu" "F.Mask" "F.Paste")
			(net "GND")
		)
		(pad "AH45" smd circle
			(at 18.999962 2.84988)
			(size 0.4572 0.4572)
			(layers "F.Cu" "F.Mask" "F.Paste")
			(net "GND")
		)
		(pad "AH46" smd circle
			(at 19.949922 2.84988)
			(size 0.4572 0.4572)
			(layers "F.Cu" "F.Mask" "F.Paste")
			(net "GND")
		)
		(pad "AH47" smd circle
			(at 20.899882 2.84988)
			(size 0.4572 0.4572)
			(layers "F.Cu" "F.Mask" "F.Paste")
			(net "GND")
		)
		(pad "AH48" smd circle
			(at 21.850096 2.84988)
			(size 0.4572 0.4572)
			(layers "F.Cu" "F.Mask" "F.Paste")
			(net "Net_2793")
		)
		(pad "AH49" smd circle
			(at 22.800056 2.84988)
			(size 0.4572 0.4572)
			(layers "F.Cu" "F.Mask" "F.Paste")
			(net "Net_2777")
		)
		(pad "AJ1" smd circle
			(at -22.800056 3.800094)
			(size 0.4572 0.4572)
			(layers "F.Cu" "F.Mask" "F.Paste")
			(net "Net_2840")
		)
		(pad "AJ2" smd circle
			(at -21.850096 3.800094)
			(size 0.4572 0.4572)
			(layers "F.Cu" "F.Mask" "F.Paste")
			(net "Net_2841")
		)
		(pad "AJ3" smd circle
			(at -20.899882 3.800094)
			(size 0.4572 0.4572)
			(layers "F.Cu" "F.Mask" "F.Paste")
			(net "GND")
		)
		(pad "AJ4" smd circle
			(at -19.949922 3.800094)
			(size 0.4572 0.4572)
			(layers "F.Cu" "F.Mask" "F.Paste")
			(net "GND")
		)
		(pad "AJ5" smd circle
			(at -18.999962 3.800094)
			(size 0.4572 0.4572)
			(layers "F.Cu" "F.Mask" "F.Paste")
			(net "GND")
		)
		(pad "AJ6" smd circle
			(at -18.050002 3.800094)
			(size 0.4572 0.4572)
			(layers "F.Cu" "F.Mask" "F.Paste")
			(net "GND")
		)
		(pad "AJ7" smd circle
			(at -17.100042 3.800094)
			(size 0.4572 0.4572)
			(layers "F.Cu" "F.Mask" "F.Paste")
			(net "SPI_PEX0_CS_N")
		)
		(pad "AJ8" smd circle
			(at -16.150082 3.800094)
			(size 0.4572 0.4572)
			(layers "F.Cu" "F.Mask" "F.Paste")
			(net "Net_2911")
		)
		(pad "AJ9" smd circle
			(at -15.200122 3.800094)
			(size 0.4572 0.4572)
			(layers "F.Cu" "F.Mask" "F.Paste")
			(net "GND")
		)
		(pad "AJ10" smd circle
			(at -14.249908 3.800094)
			(size 0.4572 0.4572)
			(layers "F.Cu" "F.Mask" "F.Paste")
			(net "P1V8_PEX")
		)
		(pad "AJ11" smd circle
			(at -13.299948 3.800094)
			(size 0.4572 0.4572)
			(layers "F.Cu" "F.Mask" "F.Paste")
			(net "GND")
		)
		(pad "AJ12" smd circle
			(at -12.349988 3.800094)
			(size 0.4572 0.4572)
			(layers "F.Cu" "F.Mask" "F.Paste")
			(net "GND")
		)
		(pad "AJ13" smd circle
			(at -11.400028 3.800094)
			(size 0.4572 0.4572)
			(layers "F.Cu" "F.Mask" "F.Paste")
			(net "PCEPLL7_VDDA18_PEX0")
		)
		(pad "AJ14" smd circle
			(at -10.450068 3.800094)
			(size 0.4572 0.4572)
			(layers "F.Cu" "F.Mask" "F.Paste")
			(net "GND")
		)
		(pad "AJ15" smd circle
			(at -9.500108 3.800094)
			(size 0.4572 0.4572)
			(layers "F.Cu" "F.Mask" "F.Paste")
			(net "P0V8_PEX0")
		)
		(pad "AJ16" smd circle
			(at -8.549894 3.800094)
			(size 0.4572 0.4572)
			(layers "F.Cu" "F.Mask" "F.Paste")
			(net "GND")
		)
		(pad "AJ17" smd circle
			(at -7.599934 3.800094)
			(size 0.4572 0.4572)
			(layers "F.Cu" "F.Mask" "F.Paste")
			(net "GND")
		)
		(pad "AJ18" smd circle
			(at -6.649974 3.800094)
			(size 0.4572 0.4572)
			(layers "F.Cu" "F.Mask" "F.Paste")
			(net "GND")
		)
		(pad "AJ19" smd circle
			(at -5.700014 3.800094)
			(size 0.4572 0.4572)
			(layers "F.Cu" "F.Mask" "F.Paste")
			(net "GND")
		)
		(pad "AJ20" smd circle
			(at -4.750054 3.800094)
			(size 0.4572 0.4572)
			(layers "F.Cu" "F.Mask" "F.Paste")
			(net "GND")
		)
		(pad "AJ21" smd circle
			(at -3.800094 3.800094)
			(size 0.4572 0.4572)
			(layers "F.Cu" "F.Mask" "F.Paste")
			(net "GND")
		)
		(pad "AJ22" smd circle
			(at -2.84988 3.800094)
			(size 0.4572 0.4572)
			(layers "F.Cu" "F.Mask" "F.Paste")
			(net "GND")
		)
		(pad "AJ23" smd circle
			(at -1.89992 3.800094)
			(size 0.4572 0.4572)
			(layers "F.Cu" "F.Mask" "F.Paste")
			(net "GND")
		)
		(pad "AJ24" smd circle
			(at -0.94996 3.800094)
			(size 0.4572 0.4572)
			(layers "F.Cu" "F.Mask" "F.Paste")
			(net "GND")
		)
		(pad "AJ25" smd circle
			(at 0 3.800094)
			(size 0.4572 0.4572)
			(layers "F.Cu" "F.Mask" "F.Paste")
			(net "GND")
		)
		(pad "AJ26" smd circle
			(at 0.94996 3.800094)
			(size 0.4572 0.4572)
			(layers "F.Cu" "F.Mask" "F.Paste")
			(net "GND")
		)
		(pad "AJ27" smd circle
			(at 1.89992 3.800094)
			(size 0.4572 0.4572)
			(layers "F.Cu" "F.Mask" "F.Paste")
			(net "GND")
		)
		(pad "AJ28" smd circle
			(at 2.84988 3.800094)
			(size 0.4572 0.4572)
			(layers "F.Cu" "F.Mask" "F.Paste")
			(net "GND")
		)
		(pad "AJ29" smd circle
			(at 3.800094 3.800094)
			(size 0.4572 0.4572)
			(layers "F.Cu" "F.Mask" "F.Paste")
			(net "GND")
		)
		(pad "AJ30" smd circle
			(at 4.750054 3.800094)
			(size 0.4572 0.4572)
			(layers "F.Cu" "F.Mask" "F.Paste")
			(net "GND")
		)
		(pad "AJ31" smd circle
			(at 5.700014 3.800094)
			(size 0.4572 0.4572)
			(layers "F.Cu" "F.Mask" "F.Paste")
			(net "GND")
		)
		(pad "AJ32" smd circle
			(at 6.649974 3.800094)
			(size 0.4572 0.4572)
			(layers "F.Cu" "F.Mask" "F.Paste")
			(net "GND")
		)
		(pad "AJ33" smd circle
			(at 7.599934 3.800094)
			(size 0.4572 0.4572)
			(layers "F.Cu" "F.Mask" "F.Paste")
			(net "GND")
		)
		(pad "AJ34" smd circle
			(at 8.549894 3.800094)
			(size 0.4572 0.4572)
			(layers "F.Cu" "F.Mask" "F.Paste")
			(net "GND")
		)
		(pad "AJ35" smd circle
			(at 9.500108 3.800094)
			(size 0.4572 0.4572)
			(layers "F.Cu" "F.Mask" "F.Paste")
			(net "GND")
		)
	)
)
